(kicad_pcb
	(version 20260206)
	(generator "pcbnew")
	(generator_version "10.0")
	(general
		(thickness 1.6)
		(legacy_teardrops no)
	)
	(paper "A4")
	(title_block
		(title "Bryce Canyon_F.DPB_16315-1-OCP.brd")
		(comment 1 "Bryce Canyon / footprints 1335-1342 of 2223")
	)
	(layers
		(0 "F.Cu" signal "TOP")
		(4 "In1.Cu" signal "L2GND")
		(6 "In2.Cu" signal "L3")
		(8 "In3.Cu" signal "L4GND")
		(10 "In4.Cu" signal "L5")
		(12 "In5.Cu" signal "L6VCC")
		(14 "In6.Cu" signal "L7VCC")
		(16 "In7.Cu" signal "L8")
		(18 "In8.Cu" signal "L9GND")
		(20 "In9.Cu" signal "L10")
		(22 "In10.Cu" signal "L11GND")
		(2 "B.Cu" signal "BOTTOM")
		(9 "F.Adhes" user "F.Adhesive")
		(11 "B.Adhes" user "B.Adhesive")
		(13 "F.Paste" user "Package Geometry/Pastemask Top")
		(15 "B.Paste" user "Package Geometry/Pastemask Bottom")
		(5 "F.SilkS" user "Ref Des/Silkscreen Top")
		(7 "B.SilkS" user "Ref Des/Silkscreen Bottom")
		(1 "F.Mask" user "Board Geometry/Soldermask Top")
		(3 "B.Mask" user "Board Geometry/Soldermask Bottom")
		(17 "Dwgs.User" user "User.Drawings")
		(19 "Cmts.User" user "User.Comments")
		(21 "Eco1.User" user "User.Eco1")
		(23 "Eco2.User" user "User.Eco2")
		(25 "Edge.Cuts" user "Board Geometry/Outline")
		(27 "Margin" user)
		(31 "F.CrtYd" user "Package Geometry/Place Bound Top")
		(29 "B.CrtYd" user "Package Geometry/Place Bound Bottom")
		(35 "F.Fab" user "Ref Des/Assembly Top")
		(33 "B.Fab" user "Ref Des/Assembly Bottom")
	)
	(footprint ""
		(layer "F.Cu")
		(at 235.823506 -346.789756)
		(property "Reference" "C48"
			(at 0 0 0)
			(layer "F.SilkS")
			(hide yes)
			(effects
				(font
					(size 1.27 1.27)
				)
			)
		)
		(property "Value" "SCD1U16V2KX-3GP"
			(at 1.1811 -2.7051 0)
			(unlocked yes)
			(layer "F.Fab")
			(hide yes)
			(effects
				(font
					(size 1.016 1.016)
					(thickness 0.1524)
				)
			)
		)
		(property "Device Type" "C402H22"
			(at 1.1811 -4.2291 0)
			(unlocked yes)
			(layer "F.Fab")
			(hide yes)
			(effects
				(font
					(size 1.016 1.016)
					(thickness 0.1524)
				)
			)
		)
		(duplicate_pad_numbers_are_jumpers no)
		(fp_rect
			(start -0.4318 0.9525)
			(end 0.4318 -0.9525)
			(stroke
				(width 0)
				(type default)
			)
			(fill no)
			(layer "F.CrtYd")
		)
		(fp_rect
			(start -0.4318 0.9525)
			(end 0.4318 -0.9525)
			(stroke
				(width 0)
				(type default)
			)
			(fill no)
			(layer "F.Fab")
		)
		(pad "1" smd custom
			(at 0 -0.4445)
			(size 0.1524 0.1524)
			(layers "F.Cu" "F.Mask" "F.Paste")
			(net "P5V_A_2_SENSE")
			(options
				(clearance outline)
				(anchor circle)
			)
			(primitives
				(gr_poly
					(pts
						(arc
							(start 0.3048 -0.2032)
							(mid 0.275042 -0.275042)
							(end 0.2032 -0.3048)
						)
						(arc
							(start -0.2032 -0.3048)
							(mid -0.275042 -0.275042)
							(end -0.3048 -0.2032)
						)
						(arc
							(start -0.3048 0.2032)
							(mid -0.275042 0.275042)
							(end -0.2032 0.3048)
						)
						(arc
							(start 0.2032 0.3048)
							(mid 0.275042 0.275042)
							(end 0.3048 0.2032)
						)
					)
					(width 0)
					(fill yes)
				)
			)
		)
		(pad "2" smd custom
			(at 0 0.4445)
			(size 0.1524 0.1524)
			(layers "F.Cu" "F.Mask" "F.Paste")
			(net "GND")
			(options
				(clearance outline)
				(anchor circle)
			)
			(primitives
				(gr_poly
					(pts
						(arc
							(start 0.3048 -0.2032)
							(mid 0.275042 -0.275042)
							(end 0.2032 -0.3048)
						)
						(arc
							(start -0.2032 -0.3048)
							(mid -0.275042 -0.275042)
							(end -0.3048 -0.2032)
						)
						(arc
							(start -0.3048 0.2032)
							(mid -0.275042 0.275042)
							(end -0.2032 0.3048)
						)
						(arc
							(start 0.2032 0.3048)
							(mid 0.275042 0.275042)
							(end 0.3048 0.2032)
						)
					)
					(width 0)
					(fill yes)
				)
			)
		)
	)
	(footprint ""
		(layer "F.Cu")
		(at 279.6032 11.5824)
		(property "Reference" "Q11"
			(at 0 0 0)
			(layer "F.SilkS")
			(hide yes)
			(effects
				(font
					(size 1.27 1.27)
				)
			)
		)
		(property "Value" "MMBT3904TT1G-GP"
			(at 0 -9.7282 0)
			(unlocked yes)
			(layer "F.Fab")
			(hide yes)
			(effects
				(font
					(size 1.016 1.016)
					(thickness 0.1524)
				)
			)
		)
		(property "Device Type" "SC75CBE1D6H36"
			(at 0 -11.6332 0)
			(unlocked yes)
			(layer "F.Fab")
			(hide yes)
			(effects
				(font
					(size 1.016 1.016)
					(thickness 0.1524)
				)
			)
		)
		(duplicate_pad_numbers_are_jumpers no)
		(fp_line
			(start -0.9652 -1.3716)
			(end -0.9652 1.3716)
			(stroke
				(width 0.1524)
				(type default)
			)
			(layer "F.SilkS")
		)
		(fp_line
			(start -0.9652 1.3716)
			(end 0.9652 1.3716)
			(stroke
				(width 0.1524)
				(type default)
			)
			(layer "F.SilkS")
		)
		(fp_line
			(start 0.9652 -1.3716)
			(end -0.9652 -1.3716)
			(stroke
				(width 0.1524)
				(type default)
			)
			(layer "F.SilkS")
		)
		(fp_line
			(start 0.9652 1.3716)
			(end 0.9652 -1.3716)
			(stroke
				(width 0.1524)
				(type default)
			)
			(layer "F.SilkS")
		)
		(fp_rect
			(start -1.0414 1.4478)
			(end 1.0414 -1.4478)
			(stroke
				(width 0)
				(type default)
			)
			(fill no)
			(layer "F.CrtYd")
		)
		(fp_poly
			(pts
				(xy -1.0414 -1.4478) (xy 1.0414 -1.4478) (xy 1.0414 1.4478) (xy -1.0414 1.4478)
			)
			(stroke
				(width 0)
				(type default)
			)
			(fill no)
			(layer "F.Fab")
		)
		(pad "B" smd custom
			(at -0.508 0.7112)
			(size 0.127 0.127)
			(layers "F.Cu" "F.Mask" "F.Paste")
			(net "VCCP")
			(options
				(clearance outline)
				(anchor circle)
			)
			(primitives
				(gr_poly
					(pts
						(arc
							(start -0.044958 0.4572)
							(mid -0.192463 0.399794)
							(end -0.254 0.254)
						)
						(xy -0.254 -0.254)
						(arc
							(start -0.253746 -0.254)
							(mid -0.192968 -0.398936)
							(end -0.04699 -0.4572)
						)
						(arc
							(start 0.04699 -0.4572)
							(mid 0.192989 -0.398958)
							(end 0.253746 -0.254)
						)
						(xy 0.254 -0.254)
						(arc
							(start 0.254 0.254)
							(mid 0.192404 0.399734)
							(end 0.044958 0.4572)
						)
					)
					(width 0)
					(fill yes)
				)
			)
		)
		(pad "C" smd custom
			(at 0 -0.7112)
			(size 0.127 0.127)
			(layers "F.Cu" "F.Mask" "F.Paste")
			(net "P12V_IN")
			(options
				(clearance outline)
				(anchor circle)
			)
			(primitives
				(gr_poly
					(pts
						(arc
							(start -0.044958 0.4572)
							(mid -0.192463 0.399794)
							(end -0.254 0.254)
						)
						(xy -0.254 -0.254)
						(arc
							(start -0.253746 -0.254)
							(mid -0.192968 -0.398936)
							(end -0.04699 -0.4572)
						)
						(arc
							(start 0.04699 -0.4572)
							(mid 0.192989 -0.398958)
							(end 0.253746 -0.254)
						)
						(xy 0.254 -0.254)
						(arc
							(start 0.254 0.254)
							(mid 0.192404 0.399734)
							(end 0.044958 0.4572)
						)
					)
					(width 0)
					(fill yes)
				)
			)
		)
		(pad "E" smd custom
			(at 0.508 0.7112)
			(size 0.127 0.127)
			(layers "F.Cu" "F.Mask" "F.Paste")
			(net "P3V3_BIAS")
			(options
				(clearance outline)
				(anchor circle)
			)
			(primitives
				(gr_poly
					(pts
						(arc
							(start -0.044958 0.4572)
							(mid -0.192463 0.399794)
							(end -0.254 0.254)
						)
						(xy -0.254 -0.254)
						(arc
							(start -0.253746 -0.254)
							(mid -0.192968 -0.398936)
							(end -0.04699 -0.4572)
						)
						(arc
							(start 0.04699 -0.4572)
							(mid 0.192989 -0.398958)
							(end 0.253746 -0.254)
						)
						(xy 0.254 -0.254)
						(arc
							(start 0.254 0.254)
							(mid 0.192404 0.399734)
							(end 0.044958 0.4572)
						)
					)
					(width 0)
					(fill yes)
				)
			)
		)
	)
	(footprint ""
		(layer "F.Cu")
		(at 332.359 -295.826942 180)
		(property "Reference" "C119"
			(at 0 0 180)
			(layer "F.SilkS")
			(hide yes)
			(effects
				(font
					(size 1.27 1.27)
				)
			)
		)
		(property "Value" "SC10U16V6KX-2GP"
			(at -0.0762 -5.1308 180)
			(unlocked yes)
			(layer "F.Fab")
			(hide yes)
			(effects
				(font
					(size 1.016 1.016)
					(thickness 0.1524)
				)
			)
		)
		(property "Device Type" "C1206H71"
			(at -0.127 -6.6548 180)
			(unlocked yes)
			(layer "F.Fab")
			(hide yes)
			(effects
				(font
					(size 1.016 1.016)
					(thickness 0.1524)
				)
			)
		)
		(duplicate_pad_numbers_are_jumpers no)
		(fp_line
			(start 1.016 2.2352)
			(end -1.016 2.2352)
			(stroke
				(width 0.1524)
				(type default)
			)
			(layer "F.SilkS")
		)
		(fp_line
			(start 1.016 0.8382)
			(end 1.016 2.2352)
			(stroke
				(width 0.1524)
				(type default)
			)
			(layer "F.SilkS")
		)
		(fp_line
			(start 1.016 -2.2352)
			(end 1.016 -0.8382)
			(stroke
				(width 0.1524)
				(type default)
			)
			(layer "F.SilkS")
		)
		(fp_line
			(start -1.016 2.2352)
			(end -1.016 0.8382)
			(stroke
				(width 0.1524)
				(type default)
			)
			(layer "F.SilkS")
		)
		(fp_line
			(start -1.016 -0.8382)
			(end -1.016 -2.2352)
			(stroke
				(width 0.1524)
				(type default)
			)
			(layer "F.SilkS")
		)
		(fp_line
			(start -1.016 -2.2352)
			(end 1.016 -2.2352)
			(stroke
				(width 0.1524)
				(type default)
			)
			(layer "F.SilkS")
		)
		(fp_rect
			(start -1.0922 2.3114)
			(end 1.0922 -2.3114)
			(stroke
				(width 0)
				(type default)
			)
			(fill no)
			(layer "F.CrtYd")
		)
		(fp_poly
			(pts
				(xy 1.0922 -2.3114) (xy 1.0922 2.3114) (xy -1.0922 2.3114) (xy -1.0922 -2.3114)
			)
			(stroke
				(width 0)
				(type default)
			)
			(fill no)
			(layer "F.Fab")
		)
		(pad "1" smd rect
			(at 0 -1.397 180)
			(size 1.651 1.27)
			(layers "F.Cu" "F.Mask" "F.Paste")
			(net "P5V_HDD6")
		)
		(pad "2" smd rect
			(at 0 1.397 180)
			(size 1.651 1.27)
			(layers "F.Cu" "F.Mask" "F.Paste")
			(net "GND")
		)
	)
	(footprint ""
		(layer "F.Cu")
		(at 428.152052 -188.954918 180)
		(property "Reference" "C319"
			(at 0 0 180)
			(layer "F.SilkS")
			(hide yes)
			(effects
				(font
					(size 1.27 1.27)
				)
			)
		)
		(property "Value" "SC4D7U25V5KX-1-GP"
			(at -0.0762 -6.1214 180)
			(unlocked yes)
			(layer "F.Fab")
			(hide yes)
			(effects
				(font
					(size 1.016 1.016)
					(thickness 0.1524)
				)
			)
		)
		(property "Device Type" "C805H58"
			(at -0.0762 -8.1534 180)
			(unlocked yes)
			(layer "F.Fab")
			(hide yes)
			(effects
				(font
					(size 1.016 1.016)
					(thickness 0.1524)
				)
			)
		)
		(duplicate_pad_numbers_are_jumpers no)
		(fp_line
			(start 0.635 0)
			(end -0.635 0)
			(stroke
				(width 0.508)
				(type default)
			)
			(layer "F.SilkS")
		)
		(fp_rect
			(start -0.9652 1.778)
			(end 0.9652 -1.778)
			(stroke
				(width 0)
				(type default)
			)
			(fill no)
			(layer "F.CrtYd")
		)
		(fp_poly
			(pts
				(xy -0.9652 -1.778) (xy 0.9652 -1.778) (xy 0.9652 1.778) (xy -0.9652 1.778)
			)
			(stroke
				(width 0)
				(type default)
			)
			(fill no)
			(layer "F.Fab")
		)
		(pad "1" smd rect
			(at 0 -0.9652 180)
			(size 1.397 1.143)
			(layers "F.Cu" "F.Mask" "F.Paste")
			(net "P12V_HDD21")
		)
		(pad "2" smd rect
			(at 0 0.9652 180)
			(size 1.397 1.143)
			(layers "F.Cu" "F.Mask" "F.Paste")
			(net "GND")
		)
	)
	(footprint ""
		(layer "F.Cu")
		(at 331.47 -61.127894 -90)
		(property "Reference" "R819"
			(at 0 0 270)
			(layer "F.SilkS")
			(hide yes)
			(effects
				(font
					(size 1.27 1.27)
				)
			)
		)
		(property "Value" "2R6F-GP"
			(at -0.0508 -4.8514 270)
			(unlocked yes)
			(layer "F.Fab")
			(hide yes)
			(effects
				(font
					(size 1.016 1.016)
					(thickness 0.1524)
				)
			)
		)
		(property "Device Type" "R1206H26"
			(at 0 -6.3754 270)
			(unlocked yes)
			(layer "F.Fab")
			(hide yes)
			(effects
				(font
					(size 1.016 1.016)
					(thickness 0.1524)
				)
			)
		)
		(duplicate_pad_numbers_are_jumpers no)
		(fp_line
			(start -1.016 2.2352)
			(end -1.016 -2.2352)
			(stroke
				(width 0.1524)
				(type default)
			)
			(layer "F.SilkS")
		)
		(fp_line
			(start 1.016 2.2352)
			(end -1.016 2.2352)
			(stroke
				(width 0.1524)
				(type default)
			)
			(layer "F.SilkS")
		)
		(fp_line
			(start -1.016 -2.2352)
			(end 1.016 -2.2352)
			(stroke
				(width 0.1524)
				(type default)
			)
			(layer "F.SilkS")
		)
		(fp_line
			(start 1.016 -2.2352)
			(end 1.016 2.2352)
			(stroke
				(width 0.1524)
				(type default)
			)
			(layer "F.SilkS")
		)
		(fp_rect
			(start -1.0922 2.3114)
			(end 1.0922 -2.3114)
			(stroke
				(width 0)
				(type default)
			)
			(fill no)
			(layer "F.CrtYd")
		)
		(fp_poly
			(pts
				(xy -1.0922 -2.3114) (xy 1.0922 -2.3114) (xy 1.0922 2.3114) (xy -1.0922 2.3114)
			)
			(stroke
				(width 0)
				(type default)
			)
			(fill no)
			(layer "F.Fab")
		)
		(pad "1" smd rect
			(at 0 -1.397 270)
			(size 1.651 1.27)
			(layers "F.Cu" "F.Mask" "F.Paste")
			(net "P5V_HDD30")
		)
		(pad "2" smd rect
			(at 0 1.397 270)
			(size 1.651 1.27)
			(layers "F.Cu" "F.Mask" "F.Paste")
			(net "5V_PRE_30")
		)
	)
	(footprint ""
		(layer "F.Cu")
		(at 67.728846 -180.064918 90)
		(property "Reference" "R433"
			(at 0 0 90)
			(layer "F.SilkS")
			(hide yes)
			(effects
				(font
					(size 1.27 1.27)
				)
			)
		)
		(property "Value" "220R3F-1-GP"
			(at -0.0254 -2.5146 90)
			(unlocked yes)
			(layer "F.Fab")
			(hide yes)
			(effects
				(font
					(size 1.016 1.016)
					(thickness 0.1524)
				)
			)
		)
		(property "Device Type" "R603H22"
			(at -0.0254 -4.0386 90)
			(unlocked yes)
			(layer "F.Fab")
			(hide yes)
			(effects
				(font
					(size 1.016 1.016)
					(thickness 0.1524)
				)
			)
		)
		(duplicate_pad_numbers_are_jumpers no)
		(fp_line
			(start 0.2032 0)
			(end 0.4826 0)
			(stroke
				(width 0.2032)
				(type default)
			)
			(layer "F.SilkS")
		)
		(fp_line
			(start -0.4826 0)
			(end -0.2032 0)
			(stroke
				(width 0.2032)
				(type default)
			)
			(layer "F.SilkS")
		)
		(fp_rect
			(start -0.5842 1.3335)
			(end 0.5842 -1.3335)
			(stroke
				(width 0)
				(type default)
			)
			(fill no)
			(layer "F.CrtYd")
		)
		(fp_rect
			(start -0.5842 1.3335)
			(end 0.5842 -1.3335)
			(stroke
				(width 0)
				(type default)
			)
			(fill no)
			(layer "F.Fab")
		)
		(pad "1" smd custom
			(at 0 -0.762 90)
			(size 0.2159 0.2159)
			(layers "F.Cu" "F.Mask" "F.Paste")
			(net "HDD_PRSNT_13")
			(options
				(clearance outline)
				(anchor circle)
			)
			(primitives
				(gr_poly
					(pts
						(arc
							(start -0.3302 -0.4318)
							(mid -0.402042 -0.402042)
							(end -0.4318 -0.3302)
						)
						(arc
							(start -0.4318 0.3302)
							(mid -0.402042 0.402042)
							(end -0.3302 0.4318)
						)
						(arc
							(start 0.3302 0.4318)
							(mid 0.402042 0.402042)
							(end 0.4318 0.3302)
						)
						(arc
							(start 0.4318 -0.3302)
							(mid 0.402042 -0.402042)
							(end 0.3302 -0.4318)
						)
					)
					(width 0)
					(fill yes)
				)
			)
		)
		(pad "2" smd custom
			(at 0 0.762 90)
			(size 0.2159 0.2159)
			(layers "F.Cu" "F.Mask" "F.Paste")
			(net "DRIVE_A_13_INS")
			(options
				(clearance outline)
				(anchor circle)
			)
			(primitives
				(gr_poly
					(pts
						(arc
							(start -0.3302 -0.4318)
							(mid -0.402042 -0.402042)
							(end -0.4318 -0.3302)
						)
						(arc
							(start -0.4318 0.3302)
							(mid -0.402042 0.402042)
							(end -0.3302 0.4318)
						)
						(arc
							(start 0.3302 0.4318)
							(mid 0.402042 0.402042)
							(end 0.4318 0.3302)
						)
						(arc
							(start 0.4318 -0.3302)
							(mid 0.402042 -0.402042)
							(end 0.3302 -0.4318)
						)
					)
					(width 0)
					(fill yes)
				)
			)
		)
	)
	(footprint ""
		(layer "F.Cu")
		(at 151.327866 -139.149074 -90)
		(property "Reference" "C543"
			(at 0 0 270)
			(layer "F.SilkS")
			(hide yes)
			(effects
				(font
					(size 1.27 1.27)
				)
			)
		)
		(property "Value" "SC1U25V3KX-GP"
			(at 0 -2.8194 270)
			(unlocked yes)
			(layer "F.Fab")
			(hide yes)
			(effects
				(font
					(size 1.016 1.016)
					(thickness 0.1524)
				)
			)
		)
		(property "Device Type" "C603H36"
			(at 0 -4.3434 270)
			(unlocked yes)
			(layer "F.Fab")
			(hide yes)
			(effects
				(font
					(size 1.016 1.016)
					(thickness 0.1524)
				)
			)
		)
		(duplicate_pad_numbers_are_jumpers no)
		(fp_line
			(start 0.508 0)
			(end -0.508 0)
			(stroke
				(width 0.2032)
				(type default)
			)
			(layer "F.SilkS")
		)
		(fp_rect
			(start -0.5842 1.3335)
			(end 0.5842 -1.3335)
			(stroke
				(width 0)
				(type default)
			)
			(fill no)
			(layer "F.CrtYd")
		)
		(fp_rect
			(start -0.5842 1.3335)
			(end 0.5842 -1.3335)
			(stroke
				(width 0)
				(type default)
			)
			(fill no)
			(layer "F.Fab")
		)
		(pad "1" smd custom
			(at 0 -0.762 270)
			(size 0.2159 0.2159)
			(layers "F.Cu" "F.Mask" "F.Paste")
			(net "AGND_CURRENT_MONOA")
			(options
				(clearance outline)
				(anchor circle)
			)
			(primitives
				(gr_poly
					(pts
						(arc
							(start -0.3302 -0.4318)
							(mid -0.402042 -0.402042)
							(end -0.4318 -0.3302)
						)
						(arc
							(start -0.4318 0.3302)
							(mid -0.402042 0.402042)
							(end -0.3302 0.4318)
						)
						(arc
							(start 0.3302 0.4318)
							(mid 0.402042 0.402042)
							(end 0.4318 0.3302)
						)
						(arc
							(start 0.4318 -0.3302)
							(mid 0.402042 -0.402042)
							(end 0.3302 -0.4318)
						)
					)
					(width 0)
					(fill yes)
				)
			)
		)
		(pad "2" smd custom
			(at 0 0.762 270)
			(size 0.2159 0.2159)
			(layers "F.Cu" "F.Mask" "F.Paste")
			(net "MB0_P12V_HS")
			(options
				(clearance outline)
				(anchor circle)
			)
			(primitives
				(gr_poly
					(pts
						(arc
							(start -0.3302 -0.4318)
							(mid -0.402042 -0.402042)
							(end -0.4318 -0.3302)
						)
						(arc
							(start -0.4318 0.3302)
							(mid -0.402042 0.402042)
							(end -0.3302 0.4318)
						)
						(arc
							(start 0.3302 0.4318)
							(mid 0.402042 0.402042)
							(end 0.4318 0.3302)
						)
						(arc
							(start 0.4318 -0.3302)
							(mid 0.402042 -0.402042)
							(end 0.3302 -0.4318)
						)
					)
					(width 0)
					(fill yes)
				)
			)
		)
	)
	(footprint ""
		(layer "F.Cu")
		(at 401.80895 -171.809918 -90)
		(property "Reference" "R605"
			(at 0 0 270)
			(layer "F.SilkS")
			(hide yes)
			(effects
				(font
					(size 1.27 1.27)
				)
			)
		)
		(property "Value" "300KR2F-GP"
			(at 0.064008 -3.993896 270)
			(unlocked yes)
			(layer "F.Fab")
			(hide yes)
			(effects
				(font
					(size 1.016 1.016)
					(thickness 0.1524)
				)
			)
		)
		(property "Device Type" "R402H16"
			(at 0.064008 -5.517896 270)
			(unlocked yes)
			(layer "F.Fab")
			(hide yes)
			(effects
				(font
					(size 1.016 1.016)
					(thickness 0.1524)
				)
			)
		)
		(duplicate_pad_numbers_are_jumpers no)
		(fp_line
			(start -0.508 -0.9398)
			(end -0.508 0.9398)
			(stroke
				(width 0.1524)
				(type default)
			)
			(layer "F.SilkS")
		)
		(fp_line
			(start 0.508 -0.9398)
			(end -0.508 -0.9398)
			(stroke
				(width 0.1524)
				(type default)
			)
			(layer "F.SilkS")
		)
		(fp_rect
			(start -0.508 0.9398)
			(end 0.508 -0.9398)
			(stroke
				(width 0)
				(type default)
			)
			(fill no)
			(layer "F.CrtYd")
		)
		(fp_rect
			(start -0.508 0.9398)
			(end 0.508 -0.9398)
			(stroke
				(width 0)
				(type default)
			)
			(fill no)
			(layer "F.Fab")
		)
		(pad "1" smd custom
			(at 0 -0.4445 270)
			(size 0.1397 0.1397)
			(layers "F.Cu" "F.Mask" "F.Paste")
			(net "SW_HDD_N20")
			(options
				(clearance outline)
				(anchor circle)
			)
			(primitives
				(gr_poly
					(pts
						(arc
							(start -0.1778 -0.2794)
							(mid -0.249642 -0.249642)
							(end -0.2794 -0.1778)
						)
						(arc
							(start -0.2794 0.1778)
							(mid -0.249642 0.249642)
							(end -0.1778 0.2794)
						)
						(arc
							(start 0.1778 0.2794)
							(mid 0.249642 0.249642)
							(end 0.2794 0.1778)
						)
						(arc
							(start 0.2794 -0.1778)
							(mid 0.249642 -0.249642)
							(end 0.1778 -0.2794)
						)
					)
					(width 0)
					(fill yes)
				)
			)
		)
		(pad "2" smd custom
			(at 0 0.4445 270)
			(size 0.1397 0.1397)
			(layers "F.Cu" "F.Mask" "F.Paste")
			(net "P12V_A")
			(options
				(clearance outline)
				(anchor circle)
			)
			(primitives
				(gr_poly
					(pts
						(arc
							(start -0.1778 -0.2794)
							(mid -0.249642 -0.249642)
							(end -0.2794 -0.1778)
						)
						(arc
							(start -0.2794 0.1778)
							(mid -0.249642 0.249642)
							(end -0.1778 0.2794)
						)
						(arc
							(start 0.1778 0.2794)
							(mid 0.249642 0.249642)
							(end 0.2794 0.1778)
						)
						(arc
							(start 0.2794 -0.1778)
							(mid 0.249642 -0.249642)
							(end 0.1778 -0.2794)
						)
					)
					(width 0)
					(fill yes)
				)
			)
		)
	)
)
